(kicad_pcb
	(version 20260206)
	(generator "pcbnew")
	(generator_version "10.0")
	(general
		(thickness 1.6)
		(legacy_teardrops no)
	)
	(paper "A4")
	(title_block
		(title "dpb — 14545-sa.0730WZS0815.brd")
		(comment 1 "Honey Badger (Wiwynn) / footprints 462-468 of 1066")
	)
	(layers
		(0 "F.Cu" signal "TOP")
		(4 "In1.Cu" signal "L2GND")
		(6 "In2.Cu" signal "L3")
		(8 "In3.Cu" signal "L4VCC")
		(10 "In4.Cu" signal "L5VCC")
		(12 "In5.Cu" signal "L6")
		(14 "In6.Cu" signal "L7GND")
		(2 "B.Cu" signal "BOTTOM")
		(9 "F.Adhes" user "F.Adhesive")
		(11 "B.Adhes" user "B.Adhesive")
		(13 "F.Paste" user "Package Geometry/Pastemask Top")
		(15 "B.Paste" user "Package Geometry/Pastemask Bottom")
		(5 "F.SilkS" user "Ref Des/Silkscreen Top")
		(7 "B.SilkS" user "Ref Des/Silkscreen Bottom")
		(1 "F.Mask" user "Board Geometry/Soldermask Top")
		(3 "B.Mask" user "Board Geometry/Soldermask Bottom")
		(17 "Dwgs.User" user "User.Drawings")
		(19 "Cmts.User" user "User.Comments")
		(21 "Eco1.User" user "User.Eco1")
		(23 "Eco2.User" user "User.Eco2")
		(25 "Edge.Cuts" user "Board Geometry/Outline")
		(27 "Margin" user)
		(31 "F.CrtYd" user "Package Geometry/Place Bound Top")
		(29 "B.CrtYd" user "Package Geometry/Place Bound Bottom")
		(35 "F.Fab" user "Ref Des/Assembly Top")
		(33 "B.Fab" user "Ref Des/Assembly Bottom")
	)
	(footprint ""
		(layer "F.Cu")
		(at 45.338746 -414.810702 90)
		(property "Reference" "U32"
			(at 0 0 90)
			(layer "F.SilkS")
			(hide yes)
			(effects
				(font
					(size 1.27 1.27)
				)
			)
		)
		(property "Value" "P2003EVG-GP"
			(at 0 -11.1252 90)
			(unlocked yes)
			(layer "F.Fab")
			(hide yes)
			(effects
				(font
					(size 1.016 1.016)
					(thickness 0.1524)
				)
			)
		)
		(property "Device Type" "SOIC8H79"
			(at 0 -12.6492 90)
			(unlocked yes)
			(layer "F.Fab")
			(hide yes)
			(effects
				(font
					(size 1.016 1.016)
					(thickness 0.1524)
				)
			)
		)
		(duplicate_pad_numbers_are_jumpers no)
		(fp_line
			(start 2.1336 -1.4224)
			(end -2.7432 -1.4224)
			(stroke
				(width 0.1524)
				(type default)
			)
			(layer "F.SilkS")
		)
		(fp_line
			(start -2.7432 -1.4224)
			(end -2.7432 1.4224)
			(stroke
				(width 0.1524)
				(type default)
			)
			(layer "F.SilkS")
		)
		(fp_line
			(start -2.7432 -0.508)
			(end -2.2352 0)
			(stroke
				(width 0.1524)
				(type default)
			)
			(layer "F.SilkS")
		)
		(fp_line
			(start -2.2352 0)
			(end -2.7432 0.508)
			(stroke
				(width 0.1524)
				(type default)
			)
			(layer "F.SilkS")
		)
		(fp_line
			(start 2.1336 1.4224)
			(end 2.1336 -1.4224)
			(stroke
				(width 0.1524)
				(type default)
			)
			(layer "F.SilkS")
		)
		(fp_line
			(start -2.7432 1.4224)
			(end 2.1336 1.4224)
			(stroke
				(width 0.1524)
				(type default)
			)
			(layer "F.SilkS")
		)
		(fp_line
			(start -2.6162 3.429)
			(end -2.6162 1.4732)
			(stroke
				(width 0.4064)
				(type default)
			)
			(layer "F.SilkS")
		)
		(fp_poly
			(pts
				(xy 2.2098 -1.4224) (xy 2.2098 1.4224) (xy -2.2225 1.4224) (xy -2.2225 -1.4224)
			)
			(stroke
				(width 0)
				(type default)
			)
			(fill yes)
			(layer "F.SilkS")
		)
		(fp_rect
			(start -2.4511 2.9972)
			(end 2.4511 -2.9972)
			(stroke
				(width 0)
				(type default)
			)
			(fill no)
			(layer "F.CrtYd")
		)
		(fp_poly
			(pts
				(xy -2.8194 3.6322) (xy -2.8194 -3.6322) (xy 2.8194 -3.6322) (xy 2.8194 -2.2987) (xy 2.4511 -2.2987)
				(xy 2.4511 -2.9972) (xy -2.4511 -2.9972) (xy -2.4511 2.9972) (xy 2.4511 2.9972) (xy 2.4511 -2.286)
				(xy 2.8194 -2.286) (xy 2.8194 3.6322)
			)
			(stroke
				(width 0)
				(type default)
			)
			(fill no)
			(layer "F.CrtYd")
		)
		(fp_rect
			(start -2.8194 3.6322)
			(end 2.8194 -3.6322)
			(stroke
				(width 0)
				(type default)
			)
			(fill no)
			(layer "F.Fab")
		)
		(pad "1" smd rect
			(at -1.905 2.54 90)
			(size 0.635 1.651)
			(layers "F.Cu" "F.Mask" "F.Paste")
			(net "P12V")
		)
		(pad "2" smd rect
			(at -0.635 2.54 90)
			(size 0.635 1.651)
			(layers "F.Cu" "F.Mask" "F.Paste")
			(net "P12V")
		)
		(pad "3" smd rect
			(at 0.635 2.54 90)
			(size 0.635 1.651)
			(layers "F.Cu" "F.Mask" "F.Paste")
			(net "P12V")
		)
		(pad "4" smd rect
			(at 1.905 2.54 90)
			(size 0.635 1.651)
			(layers "F.Cu" "F.Mask" "F.Paste")
			(net "SW_HDD10_N")
		)
		(pad "5" smd rect
			(at 1.905 -2.54 90)
			(size 0.635 1.651)
			(layers "F.Cu" "F.Mask" "F.Paste")
			(net "P12V_HDD10")
		)
		(pad "6" smd rect
			(at 0.635 -2.54 90)
			(size 0.635 1.651)
			(layers "F.Cu" "F.Mask" "F.Paste")
			(net "P12V_HDD10")
		)
		(pad "7" smd rect
			(at -0.635 -2.54 90)
			(size 0.635 1.651)
			(layers "F.Cu" "F.Mask" "F.Paste")
			(net "P12V_HDD10")
		)
		(pad "8" smd rect
			(at -1.905 -2.54 90)
			(size 0.635 1.651)
			(layers "F.Cu" "F.Mask" "F.Paste")
			(net "P12V_HDD10")
		)
	)
	(footprint ""
		(layer "F.Cu")
		(at 59.943746 -10.8077 90)
		(property "Reference" "PC24"
			(at 0 0 90)
			(layer "F.SilkS")
			(hide yes)
			(effects
				(font
					(size 1.27 1.27)
				)
			)
		)
		(property "Value" "SC22U25V5MX-GP"
			(at -0.0762 -6.1214 90)
			(unlocked yes)
			(layer "F.Fab")
			(hide yes)
			(effects
				(font
					(size 1.016 1.016)
					(thickness 0.1524)
				)
			)
		)
		(property "Device Type" "C805H58"
			(at -0.0762 -8.1534 90)
			(unlocked yes)
			(layer "F.Fab")
			(hide yes)
			(effects
				(font
					(size 1.016 1.016)
					(thickness 0.1524)
				)
			)
		)
		(duplicate_pad_numbers_are_jumpers no)
		(fp_line
			(start 0.635 0)
			(end -0.635 0)
			(stroke
				(width 0.508)
				(type default)
			)
			(layer "F.SilkS")
		)
		(fp_rect
			(start -0.9652 1.778)
			(end 0.9652 -1.778)
			(stroke
				(width 0)
				(type default)
			)
			(fill no)
			(layer "F.CrtYd")
		)
		(fp_poly
			(pts
				(xy -0.9652 -1.778) (xy 0.9652 -1.778) (xy 0.9652 1.778) (xy -0.9652 1.778)
			)
			(stroke
				(width 0)
				(type default)
			)
			(fill no)
			(layer "F.Fab")
		)
		(pad "1" smd rect
			(at 0 -0.9652 90)
			(size 1.397 1.143)
			(layers "F.Cu" "F.Mask" "F.Paste")
			(net "P5VB_12VIN")
		)
		(pad "2" smd rect
			(at 0 0.9652 90)
			(size 1.397 1.143)
			(layers "F.Cu" "F.Mask" "F.Paste")
			(net "GND")
		)
	)
	(footprint ""
		(layer "F.Cu")
		(at 192.913 -487.934)
		(property "Reference" "C110"
			(at 0 0 0)
			(layer "F.SilkS")
			(hide yes)
			(effects
				(font
					(size 1.27 1.27)
				)
			)
		)
		(property "Value" "SCD1U10V2KX-5GP"
			(at 1.1811 -2.7051 0)
			(unlocked yes)
			(layer "F.Fab")
			(hide yes)
			(effects
				(font
					(size 1.016 1.016)
					(thickness 0.1524)
				)
			)
		)
		(property "Device Type" "C402H22"
			(at 1.1811 -4.2291 0)
			(unlocked yes)
			(layer "F.Fab")
			(hide yes)
			(effects
				(font
					(size 1.016 1.016)
					(thickness 0.1524)
				)
			)
		)
		(duplicate_pad_numbers_are_jumpers no)
		(fp_rect
			(start -0.4318 0.9525)
			(end 0.4318 -0.9525)
			(stroke
				(width 0)
				(type default)
			)
			(fill no)
			(layer "F.CrtYd")
		)
		(fp_rect
			(start -0.4318 0.9525)
			(end 0.4318 -0.9525)
			(stroke
				(width 0)
				(type default)
			)
			(fill no)
			(layer "F.Fab")
		)
		(pad "1" smd custom
			(at 0 -0.4445)
			(size 0.1524 0.1524)
			(layers "F.Cu" "F.Mask" "F.Paste")
			(net "P3V3")
			(options
				(clearance outline)
				(anchor circle)
			)
			(primitives
				(gr_poly
					(pts
						(arc
							(start 0.3048 -0.2032)
							(mid 0.275042 -0.275042)
							(end 0.2032 -0.3048)
						)
						(arc
							(start -0.2032 -0.3048)
							(mid -0.275042 -0.275042)
							(end -0.3048 -0.2032)
						)
						(arc
							(start -0.3048 0.2032)
							(mid -0.275042 0.275042)
							(end -0.2032 0.3048)
						)
						(arc
							(start 0.2032 0.3048)
							(mid 0.275042 0.275042)
							(end 0.3048 0.2032)
						)
					)
					(width 0)
					(fill yes)
				)
			)
		)
		(pad "2" smd custom
			(at 0 0.4445)
			(size 0.1524 0.1524)
			(layers "F.Cu" "F.Mask" "F.Paste")
			(net "GND")
			(options
				(clearance outline)
				(anchor circle)
			)
			(primitives
				(gr_poly
					(pts
						(arc
							(start 0.3048 -0.2032)
							(mid 0.275042 -0.275042)
							(end 0.2032 -0.3048)
						)
						(arc
							(start -0.2032 -0.3048)
							(mid -0.275042 -0.275042)
							(end -0.3048 -0.2032)
						)
						(arc
							(start -0.3048 0.2032)
							(mid -0.275042 0.275042)
							(end -0.2032 0.3048)
						)
						(arc
							(start 0.2032 0.3048)
							(mid 0.275042 0.275042)
							(end 0.3048 0.2032)
						)
					)
					(width 0)
					(fill yes)
				)
			)
		)
	)
	(footprint ""
		(layer "F.Cu")
		(at 11.8872 -104.2924 180)
		(property "Reference" "R406"
			(at 0 0 180)
			(layer "F.SilkS")
			(hide yes)
			(effects
				(font
					(size 1.27 1.27)
				)
			)
		)
		(property "Value" "10KR2F-2-GP"
			(at 0.064008 -3.993896 180)
			(unlocked yes)
			(layer "F.Fab")
			(hide yes)
			(effects
				(font
					(size 1.016 1.016)
					(thickness 0.1524)
				)
			)
		)
		(property "Device Type" "R402H16"
			(at 0.064008 -5.517896 180)
			(unlocked yes)
			(layer "F.Fab")
			(hide yes)
			(effects
				(font
					(size 1.016 1.016)
					(thickness 0.1524)
				)
			)
		)
		(duplicate_pad_numbers_are_jumpers no)
		(fp_line
			(start 0.508 -0.9398)
			(end -0.508 -0.9398)
			(stroke
				(width 0.1524)
				(type default)
			)
			(layer "F.SilkS")
		)
		(fp_line
			(start -0.508 -0.9398)
			(end -0.508 0.9398)
			(stroke
				(width 0.1524)
				(type default)
			)
			(layer "F.SilkS")
		)
		(fp_rect
			(start -0.508 0.9398)
			(end 0.508 -0.9398)
			(stroke
				(width 0)
				(type default)
			)
			(fill no)
			(layer "F.CrtYd")
		)
		(fp_rect
			(start -0.508 0.9398)
			(end 0.508 -0.9398)
			(stroke
				(width 0)
				(type default)
			)
			(fill no)
			(layer "F.Fab")
		)
		(pad "1" smd custom
			(at 0 -0.4445 180)
			(size 0.1397 0.1397)
			(layers "F.Cu" "F.Mask" "F.Paste")
			(net "P3V3")
			(options
				(clearance outline)
				(anchor circle)
			)
			(primitives
				(gr_poly
					(pts
						(arc
							(start -0.1778 -0.2794)
							(mid -0.249642 -0.249642)
							(end -0.2794 -0.1778)
						)
						(arc
							(start -0.2794 0.1778)
							(mid -0.249642 0.249642)
							(end -0.1778 0.2794)
						)
						(arc
							(start 0.1778 0.2794)
							(mid 0.249642 0.249642)
							(end 0.2794 0.1778)
						)
						(arc
							(start 0.2794 -0.1778)
							(mid 0.249642 -0.249642)
							(end 0.1778 -0.2794)
						)
					)
					(width 0)
					(fill yes)
				)
			)
		)
		(pad "2" smd custom
			(at 0 0.4445 180)
			(size 0.1397 0.1397)
			(layers "F.Cu" "F.Mask" "F.Paste")
			(net "DPB_HW_REV")
			(options
				(clearance outline)
				(anchor circle)
			)
			(primitives
				(gr_poly
					(pts
						(arc
							(start -0.1778 -0.2794)
							(mid -0.249642 -0.249642)
							(end -0.2794 -0.1778)
						)
						(arc
							(start -0.2794 0.1778)
							(mid -0.249642 0.249642)
							(end -0.1778 0.2794)
						)
						(arc
							(start 0.1778 0.2794)
							(mid 0.249642 0.249642)
							(end 0.2794 0.1778)
						)
						(arc
							(start 0.2794 -0.1778)
							(mid 0.249642 -0.249642)
							(end 0.1778 -0.2794)
						)
					)
					(width 0)
					(fill yes)
				)
			)
		)
	)
	(footprint ""
		(layer "F.Cu")
		(at 55.9562 -396.9004 180)
		(property "Reference" "C210"
			(at 0 0 180)
			(layer "F.SilkS")
			(hide yes)
			(effects
				(font
					(size 1.27 1.27)
				)
			)
		)
		(property "Value" "SC10U25V6KX-1GP"
			(at -0.0762 -5.1308 180)
			(unlocked yes)
			(layer "F.Fab")
			(hide yes)
			(effects
				(font
					(size 1.016 1.016)
					(thickness 0.1524)
				)
			)
		)
		(property "Device Type" "C1206H71"
			(at -0.127 -6.6548 180)
			(unlocked yes)
			(layer "F.Fab")
			(hide yes)
			(effects
				(font
					(size 1.016 1.016)
					(thickness 0.1524)
				)
			)
		)
		(duplicate_pad_numbers_are_jumpers no)
		(fp_line
			(start 1.016 2.2352)
			(end -1.016 2.2352)
			(stroke
				(width 0.1524)
				(type default)
			)
			(layer "F.SilkS")
		)
		(fp_line
			(start 1.016 0.8382)
			(end 1.016 2.2352)
			(stroke
				(width 0.1524)
				(type default)
			)
			(layer "F.SilkS")
		)
		(fp_line
			(start 1.016 -2.2352)
			(end 1.016 -0.8382)
			(stroke
				(width 0.1524)
				(type default)
			)
			(layer "F.SilkS")
		)
		(fp_line
			(start -1.016 2.2352)
			(end -1.016 0.8382)
			(stroke
				(width 0.1524)
				(type default)
			)
			(layer "F.SilkS")
		)
		(fp_line
			(start -1.016 -0.8382)
			(end -1.016 -2.2352)
			(stroke
				(width 0.1524)
				(type default)
			)
			(layer "F.SilkS")
		)
		(fp_line
			(start -1.016 -2.2352)
			(end 1.016 -2.2352)
			(stroke
				(width 0.1524)
				(type default)
			)
			(layer "F.SilkS")
		)
		(fp_rect
			(start -1.0922 2.3114)
			(end 1.0922 -2.3114)
			(stroke
				(width 0)
				(type default)
			)
			(fill no)
			(layer "F.CrtYd")
		)
		(fp_poly
			(pts
				(xy 1.0922 -2.3114) (xy 1.0922 2.3114) (xy -1.0922 2.3114) (xy -1.0922 -2.3114)
			)
			(stroke
				(width 0)
				(type default)
			)
			(fill no)
			(layer "F.Fab")
		)
		(pad "1" smd rect
			(at 0 -1.397 180)
			(size 1.651 1.27)
			(layers "F.Cu" "F.Mask" "F.Paste")
			(net "P12V_HDD6")
		)
		(pad "2" smd rect
			(at 0 1.397 180)
			(size 1.651 1.27)
			(layers "F.Cu" "F.Mask" "F.Paste")
			(net "GND")
		)
	)
	(footprint ""
		(layer "F.Cu")
		(at 216.910412 -70.592696)
		(property "Reference" "R167"
			(at 0 0 0)
			(layer "F.SilkS")
			(hide yes)
			(effects
				(font
					(size 1.27 1.27)
				)
			)
		)
		(property "Value" "220R3F-1-GP"
			(at -0.0254 -2.5146 0)
			(unlocked yes)
			(layer "F.Fab")
			(hide yes)
			(effects
				(font
					(size 1.016 1.016)
					(thickness 0.1524)
				)
			)
		)
		(property "Device Type" "R603H22"
			(at -0.0254 -4.0386 0)
			(unlocked yes)
			(layer "F.Fab")
			(hide yes)
			(effects
				(font
					(size 1.016 1.016)
					(thickness 0.1524)
				)
			)
		)
		(duplicate_pad_numbers_are_jumpers no)
		(fp_line
			(start -0.4826 0)
			(end -0.2032 0)
			(stroke
				(width 0.2032)
				(type default)
			)
			(layer "F.SilkS")
		)
		(fp_line
			(start 0.2032 0)
			(end 0.4826 0)
			(stroke
				(width 0.2032)
				(type default)
			)
			(layer "F.SilkS")
		)
		(fp_rect
			(start -0.5842 1.3335)
			(end 0.5842 -1.3335)
			(stroke
				(width 0)
				(type default)
			)
			(fill no)
			(layer "F.CrtYd")
		)
		(fp_rect
			(start -0.5842 1.3335)
			(end 0.5842 -1.3335)
			(stroke
				(width 0)
				(type default)
			)
			(fill no)
			(layer "F.Fab")
		)
		(pad "1" smd custom
			(at 0 -0.762)
			(size 0.2159 0.2159)
			(layers "F.Cu" "F.Mask" "F.Paste")
			(net "HDD_PRSNT_NET4")
			(options
				(clearance outline)
				(anchor circle)
			)
			(primitives
				(gr_poly
					(pts
						(arc
							(start -0.3302 -0.4318)
							(mid -0.402042 -0.402042)
							(end -0.4318 -0.3302)
						)
						(arc
							(start -0.4318 0.3302)
							(mid -0.402042 0.402042)
							(end -0.3302 0.4318)
						)
						(arc
							(start 0.3302 0.4318)
							(mid 0.402042 0.402042)
							(end 0.4318 0.3302)
						)
						(arc
							(start 0.4318 -0.3302)
							(mid 0.402042 -0.402042)
							(end 0.3302 -0.4318)
						)
					)
					(width 0)
					(fill yes)
				)
			)
		)
		(pad "2" smd custom
			(at 0 0.762)
			(size 0.2159 0.2159)
			(layers "F.Cu" "F.Mask" "F.Paste")
			(net "HDD_PRSNT4")
			(options
				(clearance outline)
				(anchor circle)
			)
			(primitives
				(gr_poly
					(pts
						(arc
							(start -0.3302 -0.4318)
							(mid -0.402042 -0.402042)
							(end -0.4318 -0.3302)
						)
						(arc
							(start -0.4318 0.3302)
							(mid -0.402042 0.402042)
							(end -0.3302 0.4318)
						)
						(arc
							(start 0.3302 0.4318)
							(mid 0.402042 0.402042)
							(end 0.4318 0.3302)
						)
						(arc
							(start 0.4318 -0.3302)
							(mid 0.402042 -0.402042)
							(end 0.3302 -0.4318)
						)
					)
					(width 0)
					(fill yes)
				)
			)
		)
	)
	(footprint ""
		(layer "F.Cu")
		(at 77.977746 -86.1187 -90)
		(property "Reference" "R239"
			(at 0 0 270)
			(layer "F.SilkS")
			(hide yes)
			(effects
				(font
					(size 1.27 1.27)
				)
			)
		)
		(property "Value" "0R2J-2-GP"
			(at 0.064008 -3.993896 270)
			(unlocked yes)
			(layer "F.Fab")
			(hide yes)
			(effects
				(font
					(size 1.016 1.016)
					(thickness 0.1524)
				)
			)
		)
		(property "Device Type" "R402H16"
			(at 0.064008 -5.517896 270)
			(unlocked yes)
			(layer "F.Fab")
			(hide yes)
			(effects
				(font
					(size 1.016 1.016)
					(thickness 0.1524)
				)
			)
		)
		(duplicate_pad_numbers_are_jumpers no)
		(fp_line
			(start -0.508 -0.9398)
			(end -0.508 0.9398)
			(stroke
				(width 0.1524)
				(type default)
			)
			(layer "F.SilkS")
		)
		(fp_line
			(start 0.508 -0.9398)
			(end -0.508 -0.9398)
			(stroke
				(width 0.1524)
				(type default)
			)
			(layer "F.SilkS")
		)
		(fp_rect
			(start -0.508 0.9398)
			(end 0.508 -0.9398)
			(stroke
				(width 0)
				(type default)
			)
			(fill no)
			(layer "F.CrtYd")
		)
		(fp_rect
			(start -0.508 0.9398)
			(end 0.508 -0.9398)
			(stroke
				(width 0)
				(type default)
			)
			(fill no)
			(layer "F.Fab")
		)
		(pad "1" smd custom
			(at 0 -0.4445 270)
			(size 0.1397 0.1397)
			(layers "F.Cu" "F.Mask" "F.Paste")
			(net "DRIVE_PWR9")
			(options
				(clearance outline)
				(anchor circle)
			)
			(primitives
				(gr_poly
					(pts
						(arc
							(start -0.1778 -0.2794)
							(mid -0.249642 -0.249642)
							(end -0.2794 -0.1778)
						)
						(arc
							(start -0.2794 0.1778)
							(mid -0.249642 0.249642)
							(end -0.1778 0.2794)
						)
						(arc
							(start 0.1778 0.2794)
							(mid 0.249642 0.249642)
							(end 0.2794 0.1778)
						)
						(arc
							(start 0.2794 -0.1778)
							(mid 0.249642 -0.249642)
							(end 0.1778 -0.2794)
						)
					)
					(width 0)
					(fill yes)
				)
			)
		)
		(pad "2" smd custom
			(at 0 0.4445 270)
			(size 0.1397 0.1397)
			(layers "F.Cu" "F.Mask" "F.Paste")
			(net "SW_PWR_HDD9")
			(options
				(clearance outline)
				(anchor circle)
			)
			(primitives
				(gr_poly
					(pts
						(arc
							(start -0.1778 -0.2794)
							(mid -0.249642 -0.249642)
							(end -0.2794 -0.1778)
						)
						(arc
							(start -0.2794 0.1778)
							(mid -0.249642 0.249642)
							(end -0.1778 0.2794)
						)
						(arc
							(start 0.1778 0.2794)
							(mid 0.249642 0.249642)
							(end 0.2794 0.1778)
						)
						(arc
							(start 0.2794 -0.1778)
							(mid 0.249642 -0.249642)
							(end 0.1778 -0.2794)
						)
					)
					(width 0)
					(fill yes)
				)
			)
		)
	)
)
